# BASEBOARD_FAB2 (Tioga Pass) — schematic netlist excerpt (pin names and nets, part order shuffled) for the footprints in the layout excerpt that follows; sources: Cadence DE-HDL packaged netlist, KiCad conversion of Wiwynn_Tioga_Pass_MB.brd

C3G8  CAP  10UF 4V 20% X6S  pkg 0603LF  page 233 : A = PVPP_GHJ ; B = GND
R2P2  RES  1.00K 1% CHIP  pkg 0402  page 111 : A = SPI_PCH_IO2 ; B = XDP_DEBUG_CONSENT_N
R1B16  RES  10.0 1% CHIP  pkg 0402  page 226 : A = VSENSE_PVDDQ_KLM_P ; B = VR_PVDDQ_KLM_AVSP

(kicad_pcb
	(version 20260206)
	(generator "pcbnew")
	(generator_version "10.0")
	(general
		(thickness 1.6)
		(legacy_teardrops no)
	)
	(paper "A4")
	(title_block
		(title "Wiwynn_Tioga_Pass_MB.brd")
		(comment 1 "Tioga Pass / footprints 1940-1942 of 4770")
	)
	(layers
		(0 "F.Cu" signal "TOP")
		(4 "In1.Cu" signal "L2GND")
		(6 "In2.Cu" signal "L3")
		(8 "In3.Cu" signal "L4GND")
		(10 "In4.Cu" signal "L5")
		(12 "In5.Cu" signal "L6GND")
		(14 "In6.Cu" signal "L7VCC")
		(16 "In7.Cu" signal "L8VCC")
		(18 "In8.Cu" signal "L9GND")
		(20 "In9.Cu" signal "L10")
		(22 "In10.Cu" signal "L11GND")
		(24 "In11.Cu" signal "L12")
		(26 "In12.Cu" signal "L13GND")
		(2 "B.Cu" signal "BOTTOM")
		(9 "F.Adhes" user "F.Adhesive")
		(11 "B.Adhes" user "B.Adhesive")
		(13 "F.Paste" user "Package Geometry/Pastemask Top")
		(15 "B.Paste" user "Package Geometry/Pastemask Bottom")
		(5 "F.SilkS" user "Ref Des/Silkscreen Top")
		(7 "B.SilkS" user "Ref Des/Silkscreen Bottom")
		(1 "F.Mask" user "Board Geometry/Soldermask Top")
		(3 "B.Mask" user "Board Geometry/Soldermask Bottom")
		(17 "Dwgs.User" user "User.Drawings")
		(19 "Cmts.User" user "User.Comments")
		(21 "Eco1.User" user "User.Eco1")
		(23 "Eco2.User" user "User.Eco2")
		(25 "Edge.Cuts" user "Board Geometry/Outline")
		(27 "Margin" user)
		(31 "F.CrtYd" user "Package Geometry/Place Bound Top")
		(29 "B.CrtYd" user "Package Geometry/Place Bound Bottom")
		(35 "F.Fab" user "Ref Des/Assembly Top")
		(33 "B.Fab" user "Ref Des/Assembly Bottom")
	)
	(footprint ""
		(layer "F.Cu")
		(at 374.015 -89.0905 180)
		(property "Reference" "R2P2"
			(at 0 0 180)
			(layer "F.SilkS")
			(hide yes)
			(effects
				(font
					(size 1.27 1.27)
				)
			)
		)
		(property "Value" ""
			(at 0 0 180)
			(layer "F.Fab")
			(effects
				(font
					(size 1.27 1.27)
				)
			)
		)
		(duplicate_pad_numbers_are_jumpers no)
		(fp_rect
			(start 0.2794 -0.1016)
			(end -0.2794 0.9906)
			(stroke
				(width 0)
				(type default)
			)
			(fill no)
			(layer "F.CrtYd")
		)
		(fp_line
			(start 0.2794 0.9906)
			(end 0.2794 -0.1016)
			(stroke
				(width 0.1)
				(type default)
			)
			(layer "F.Fab")
		)
		(fp_line
			(start 0.2794 -0.1016)
			(end -0.2794 -0.1016)
			(stroke
				(width 0.1)
				(type default)
			)
			(layer "F.Fab")
		)
		(fp_line
			(start -0.2794 0.9906)
			(end 0.2794 0.9906)
			(stroke
				(width 0.1)
				(type default)
			)
			(layer "F.Fab")
		)
		(fp_line
			(start -0.2794 -0.1016)
			(end -0.2794 0.9906)
			(stroke
				(width 0.1)
				(type default)
			)
			(layer "F.Fab")
		)
		(pad "1" smd rect
			(at 0 0 180)
			(size 0.508 0.508)
			(layers "F.Cu" "F.Mask" "F.Paste")
			(net "SPI_PCH_IO2")
		)
		(pad "2" smd rect
			(at 0 0.889 180)
			(size 0.508 0.508)
			(layers "F.Cu" "F.Mask" "F.Paste")
			(net "XDP_DEBUG_CONSENT_N")
		)
		(zone
			(layer "F.Cu")
			(hatch none 0.5)
			(connect_pads
				(clearance 0)
			)
			(min_thickness 0.25)
			(keepout
				(tracks allowed)
				(vias not_allowed)
				(pads allowed)
				(copperpour not_allowed)
				(footprints allowed)
			)
			(placement
				(enabled no)
				(sheetname "")
			)
			(fill
				(thermal_gap 0.5)
				(thermal_bridge_width 0.5)
				(island_removal_mode 0)
			)
			(polygon
				(pts
					(xy 373.761 -89.3445) (xy 374.269 -89.3445) (xy 374.269 -89.7255) (xy 373.761 -89.7255)
				)
			)
		)
		(zone
			(layer "F.Cu")
			(hatch none 0.5)
			(connect_pads
				(clearance 0)
			)
			(min_thickness 0.25)
			(keepout
				(tracks not_allowed)
				(vias allowed)
				(pads allowed)
				(copperpour not_allowed)
				(footprints allowed)
			)
			(placement
				(enabled no)
				(sheetname "")
			)
			(fill
				(thermal_gap 0.5)
				(thermal_bridge_width 0.5)
				(island_removal_mode 0)
			)
			(polygon
				(pts
					(xy 373.761 -89.3445) (xy 374.269 -89.3445) (xy 374.269 -89.7255) (xy 373.761 -89.7255)
				)
			)
		)
	)
	(footprint ""
		(layer "F.Cu")
		(at -3.429 -124.333 180)
		(property "Reference" "R1B16"
			(at 0 0 180)
			(layer "F.SilkS")
			(hide yes)
			(effects
				(font
					(size 1.27 1.27)
				)
			)
		)
		(property "Value" ""
			(at 0 0 180)
			(layer "F.Fab")
			(effects
				(font
					(size 1.27 1.27)
				)
			)
		)
		(duplicate_pad_numbers_are_jumpers no)
		(fp_rect
			(start 0.2794 -0.1016)
			(end -0.2794 0.9906)
			(stroke
				(width 0)
				(type default)
			)
			(fill no)
			(layer "F.CrtYd")
		)
		(fp_line
			(start 0.2794 0.9906)
			(end 0.2794 -0.1016)
			(stroke
				(width 0.1)
				(type default)
			)
			(layer "F.Fab")
		)
		(fp_line
			(start 0.2794 -0.1016)
			(end -0.2794 -0.1016)
			(stroke
				(width 0.1)
				(type default)
			)
			(layer "F.Fab")
		)
		(fp_line
			(start -0.2794 0.9906)
			(end 0.2794 0.9906)
			(stroke
				(width 0.1)
				(type default)
			)
			(layer "F.Fab")
		)
		(fp_line
			(start -0.2794 -0.1016)
			(end -0.2794 0.9906)
			(stroke
				(width 0.1)
				(type default)
			)
			(layer "F.Fab")
		)
		(pad "1" smd rect
			(at 0 0 180)
			(size 0.508 0.508)
			(layers "F.Cu" "F.Mask" "F.Paste")
			(net "VSENSE_PVDDQ_KLM_P")
		)
		(pad "2" smd rect
			(at 0 0.889 180)
			(size 0.508 0.508)
			(layers "F.Cu" "F.Mask" "F.Paste")
			(net "VR_PVDDQ_KLM_AVSP")
		)
		(zone
			(layer "F.Cu")
			(hatch none 0.5)
			(connect_pads
				(clearance 0)
			)
			(min_thickness 0.25)
			(keepout
				(tracks allowed)
				(vias not_allowed)
				(pads allowed)
				(copperpour not_allowed)
				(footprints allowed)
			)
			(placement
				(enabled no)
				(sheetname "")
			)
			(fill
				(thermal_gap 0.5)
				(thermal_bridge_width 0.5)
				(island_removal_mode 0)
			)
			(polygon
				(pts
					(xy -3.683 -124.587) (xy -3.175 -124.587) (xy -3.175 -124.968) (xy -3.683 -124.968)
				)
			)
		)
		(zone
			(layer "F.Cu")
			(hatch none 0.5)
			(connect_pads
				(clearance 0)
			)
			(min_thickness 0.25)
			(keepout
				(tracks not_allowed)
				(vias allowed)
				(pads allowed)
				(copperpour not_allowed)
				(footprints allowed)
			)
			(placement
				(enabled no)
				(sheetname "")
			)
			(fill
				(thermal_gap 0.5)
				(thermal_bridge_width 0.5)
				(island_removal_mode 0)
			)
			(polygon
				(pts
					(xy -3.683 -124.587) (xy -3.175 -124.587) (xy -3.175 -124.968) (xy -3.683 -124.968)
				)
			)
		)
	)
	(footprint ""
		(layer "F.Cu")
		(at 155.194 -3.302 90)
		(property "Reference" "C3G8"
			(at 0 0 90)
			(layer "F.SilkS")
			(hide yes)
			(effects
				(font
					(size 1.27 1.27)
				)
			)
		)
		(property "Value" ""
			(at 0 0 90)
			(layer "F.Fab")
			(effects
				(font
					(size 1.27 1.27)
				)
			)
		)
		(duplicate_pad_numbers_are_jumpers no)
		(fp_poly
			(pts
				(xy -0.4953 -0.2032) (xy 0.4953 -0.2032) (xy 0.4953 1.6002) (xy -0.4953 1.6002)
			)
			(stroke
				(width 0)
				(type default)
			)
			(fill no)
			(layer "F.CrtYd")
		)
		(fp_line
			(start 0.4953 -0.2032)
			(end 0.4953 1.6002)
			(stroke
				(width 0.1)
				(type default)
			)
			(layer "F.Fab")
		)
		(fp_line
			(start -0.4953 -0.2032)
			(end 0.4953 -0.2032)
			(stroke
				(width 0.1)
				(type default)
			)
			(layer "F.Fab")
		)
		(fp_line
			(start 0.4953 1.6002)
			(end -0.4953 1.6002)
			(stroke
				(width 0.1)
				(type default)
			)
			(layer "F.Fab")
		)
		(fp_line
			(start -0.4953 1.6002)
			(end -0.4953 -0.2032)
			(stroke
				(width 0.1)
				(type default)
			)
			(layer "F.Fab")
		)
		(pad "1" smd rect
			(at 0 0 90)
			(size 0.762 0.889)
			(layers "F.Cu" "F.Mask" "F.Paste")
			(net "PVPP_GHJ")
		)
		(pad "2" smd rect
			(at 0 1.397 90)
			(size 0.762 0.889)
			(layers "F.Cu" "F.Mask" "F.Paste")
			(net "GND")
		)
		(zone
			(layer "F.Cu")
			(hatch none 0.5)
			(connect_pads
				(clearance 0)
			)
			(min_thickness 0.25)
			(keepout
				(tracks not_allowed)
				(vias allowed)
				(pads allowed)
				(copperpour not_allowed)
				(footprints allowed)
			)
			(placement
				(enabled no)
				(sheetname "")
			)
			(fill
				(thermal_gap 0.5)
				(thermal_bridge_width 0.5)
				(island_removal_mode 0)
			)
			(polygon
				(pts
					(xy 155.6385 -2.921) (xy 155.6385 -3.683) (xy 156.1465 -3.683) (xy 156.1465 -2.921)
				)
			)
		)
	)
)
